# Lightning_PEB_EQL.xlsx — CLOCK (si-constraints)
|  |  | CLOCK (diff pair 85±10% ohm ) |  |  |  | W/Sd=5.38/6.2 for outer layout and 5.25/7.5 for inner layer  W:trace width Sd:diff Pair space |  |  |  |  |  |  |  |  |  |  |  |  |  |  |  |  |  |  |  |  |  |  |  |
| Leopard-BW to Clock Buffer of Re-timer card |  |  |  |  |  |  |  |  | PCISLT230-2-GP(PCIE1) | GF-PCIE-230P-GP(GF1) |  |  |  | PCISLT98-62-GP(CN1) | GF-PCIE-164P-5-GP(GF1) |  |  |  |  |  |  |  |  |  |  |  |  |  |  |
| CLK BUFFER OF LEOPOARD(MB)_DB1(9ZX21901BKLFT-GP-U) |  |  |  |  |  |  |  |  | PCIE X24 SLOT CONN | PCIE X24 SLOT GF | PCIE x16 SLOT of Riser Card(CN2_PCISLT164-33-GP) |  |  | PCIE X16 SLOT CONN | PCIE X16 SLOT GF | Re-timer Card(U5_9DBV0631BKLF-G) |  |  |  |  |  |  |  |  |  |  |  |  |  |
| Net Name | PKG Lengths | PCB Net Length | Differential Match | Net Name | PCB Net Length | Differential Match | MB Total Length | Differential Match | Pin of Connector | Pin of Connector | Net Name | PCB Net Length | Differential Match | Pin of Connector | Pin of Connector | Net Name | PCB Net Length | Differential Match | Total Length | Differential Match |  |  |  |  |  |  |  |  |  |
| CLK_100M_RISER1_PE2_R_DP |  | 227.51 |  | CLK_100M_RISER1_PE2_DP | 7278 |  | 7505.51 |  | A32 | A32 | CLK100_PCIE_SLOT1_P | 3378.71 |  | A13 | A13 | D85_LEOPARD_PCIE_CLK100M_P | 2808.16 |  | 13692.380000000001 |  |  |  |  |  |  |  |  |  |  |
| CLK_100M_RISER1_PE2_R_DN |  | 227.64 | yes; within 10mil | CLK_100M_RISER1_PE2_DN | 7279.44 | yes; within 10mil | 7507.08 | yes; within 10mil | A33 | A33 | CLK100_PCIE_SLOT1_N | 3378.54 | yes; within 10mil | A14 | A14 | D85_LEOPARD_PCIE_CLK100M_N | 2806.97 | yes; within 2mil | 13692.589999999998 | yes; within 5 mils |  |  |  |  |  |  |  |  |  |
| CLK BUFFER of Re-timer Card(U5_9DBV0631BKLF-G) to IDT Re-timer |  |  |  |  |  |  |  |  |  |  |  |  |  |  |  |  |  |  |  |  |  |  |  |  |  |  |  |  |  |
| Net Name | PKG Lengths | PCB Net Length | Differential Match | Net Name | PCB Net Length | Differential Match | Re-timer Card Total Length | Differential Match |  |  |  |  |  |  |  |  |  |  |  |  |  |  |  |  |  |  |  |  |  |
| D85_100M_CLKBUFF_RITIMER_R_DP |  | 93.53 |  | D85_100M_CLKBUFF_RITIMER_DP | 1999.34 |  | 2092.87 |  |  |  |  |  |  |  |  |  |  |  |  |  |  |  |  |  |  |  |  |  |  |
| D85_100M_CLKBUFF_RITIMER_R_DN |  | 97 | yes; within 5mil | D85_100M_CLKBUFF_RITIMER_DN | 1997.47 | yes; within 2mil | 2094.4700000000003 | yes; within 2mil |  |  |  |  |  |  |  |  |  |  |  |  |  |  |  |  |  |  |  |  |  |
|  |  |  |  |  |  |  |  |  | MLX-CONN144-12R-3-GP-U |  | MLX-CONN144-12R-3-GP-U |  |  |  |  |  |  |  |  |  |  |  |  |  |  |  |  |  |  |
| CLK Buffer to MINI SAS HD of Re-timer Card(CN3A~D_MLX-CONN144-12R-3-GP-U) |  |  |  |  |  |  |  |  | MiniSAS HD Connector | MiniSAS HD Cable | MiniSAS HD Connector | CN15 of PEB of PM8536 |  |  |  |  |  |  |  |  | MiniSAS HD Connector | CN15 of PEB of PM8536 |  |  |  |  |  |  |  |
| Net Name | PKG Lengths | PCB Net Length | Differential Match | Net Name | PCB Net Length | Differential Match | Re-timer Card Total Length | Differential Match | Pin of Connector | The Length of Cable | Pin of Connector | Net Name | PCB Net Length | Differential Match | Net Name | PCB Net Length | Differential Match | Total Length | Differential Match |  | Pin of Connector | Net Name | PCB Net Length | Differential Match | Net Name | PCB Net Length | Differential Match | Total Length | Differential Match |
| D85_100M_CLKBUFF_LIGHT_R_DP0 |  | 208.89 |  | D85_100M_CLKBUFF_MINI_DP0_R | 1619.87 |  | 1828.7599999999998 |  | AA1 |  | AA1 | PCIE_REFCLK_H2_P_R | 2307.4299999999998 |  | PCIE_REFCLK_H2_P | 3251.76 |  | 7387.95 |  |  |  | PCIE_REFCLK_H0_P_R | 641.07000000000005 |  | PCIE_REFCLK_H0_P | 2044.99 |  | 4514.82 |  |
| D85_100M_CLKBUFF_LIGHT_R_DN0 |  | 209.39 | yes; within 5mil | D85_100M_CLKBUFF_MINI_DN0_R | 1619.24 | yes; within 2mil | 1828.63 | yes; within 2mil | AA2 |  | AA2 | PCIE_REFCLK_H2_N_R | 2307.89 | yes; within 1mil | PCIE_REFCLK_H2_N | 3251.44 | yes; within 1mil | 7387.9600000000009 | yes; within 5 mils |  |  | PCIE_REFCLK_H0_N_R | 640.77 | yes; within 1mil | PCIE_REFCLK_H0_N | 2044.84 | yes; within 1mil | 4514.24 | yes; within 5 mils |
| D85_100M_CLKBUFF_LIGHT_R_DP1 |  | 176.44 |  | D85_100M_CLKBUFF_MINI_DP1_R | 2158.02 |  | 2334.46 |  | BA1 |  | BA1 |  |  |  |  |  |  |  |  |  |  |  |  |  |  |  |  |  |  |
| D85_100M_CLKBUFF_LIGHT_R_DN1 |  | 176.57 | yes; within 5mil | D85_100M_CLKBUFF_MINI_DN1_R | 2159.5700000000002 | yes; within 2mil | 2336.1400000000003 | yes; within 2mil | BA2 |  | BA2 |  |  |  |  |  |  |  |  |  |  |  |  |  |  |  |  |  |  |
| D85_100M_CLKBUFF_LIGHT_R_DP2 |  | 344.05 |  | D85_100M_CLKBUFF_MINI_DP2_R | 2525.5700000000002 |  | 2869.6200000000003 |  | CA1 |  | CA1 | PCIE_REFCLK_H3_P_R | 1486.06 |  | PCIE_REFCLK_H3_P | 3132.67 |  | 7488.35 |  |  |  | PCIE_REFCLK_H1_P_R | 1704.31 |  | PCIE_REFCLK_H1_P | 2254.33 |  | 6828.26 |  |
| D85_100M_CLKBUFF_LIGHT_R_DN2 |  | 344.61 | yes; within 5mil | D85_100M_CLKBUFF_MINI_DN2_R | 2526.37 | yes; within 2mil | 2870.98 | yes; within 2mil | CA2 |  | CA2 | PCIE_REFCLK_H3_N_R | 1486.23 | yes; within 1mil | PCIE_REFCLK_H3_N | 3133.1 | yes; within 1mil | 7490.3099999999995 | yes; within 5 mils |  |  | PCIE_REFCLK_H1_N_R | 1703.37 | yes; within 1mil | PCIE_REFCLK_H1_N | 2253.42 | yes; within 1mil | 6827.77 | yes; within 5 mils |
| D85_100M_CLKBUFF_LIGHT_R_DP3 |  | 273.95999999999998 |  | D85_100M_CLKBUFF_MINI_DP3_R | 3320.35 |  | 3594.31 |  | DA1 |  | DA1 |  |  |  |  |  |  |  |  |  |  |  |  |  |  |  |  |  |  |
| D85_100M_CLKBUFF_LIGHT_R_DN3 |  | 271.39 | yes; within 5mil | D85_100M_CLKBUFF_MINI_DN3_R | 3322.2 | yes; within 2mil | 3593.5899999999997 | yes; within 2mil | DA2 |  | DA2 |  |  |  |  |  |  |  |  |  |  |  |  |  |  |  |  |  |  |
|  |  |  |  |  |  |  |  |  |  |  |  | PCIE_REFCLK_D_P_R | 112.86 |  | PCIE_REFCLK_D_P | 4578.5200000000004 |  | 4691.38 |  |  |  |  |  |  |  |  |  |  |  |
|  |  |  |  |  |  |  |  |  |  |  |  | PCIE_REFCLK_D_N_R | 112.86 | yes; within 1mil | PCIE_REFCLK_D_N | 4578.92 | yes; within 1mil | 4691.78 | yes; within 1mil |  |  |  |  |  |  |  |  |  |  |
|  |  |  |  |  |  |  |  |  |  |  |  | CLKGEN_P1_R | 108.04 |  | I210_REFCLK_D_P | 6824.52 |  | 6932.56 |  |  |  |  |  |  |  |  |  |  |  |
|  |  |  |  |  |  |  |  |  |  |  |  | CLKGEN_N1_R | 108 | yes; within 1mil | I210_REFCLK_D_N | 6824.91 | yes; within 1mil | 6932.91 | yes; within 1mil |  |  |  |  |  |  |  |  |  |  |
|  |  |  |  |  | PCISLT200-5-GP(J17~19) |  |  |  |  |  |  |  |  |  |  |  |  |  |  |  |  |  |  |  |  |  |  |  |  |
| SW OF PEB(U1G_PM8546A-FEIP-GP) |  |  |  | GF8_GF-200P-8-GP | Card Edge Conn | CLK BUFFER of PDPB(EU1~4_9ZXL1231AKLFT-GP) |  |  |  |  |  |  |  |  |  |  |  |  |  |  |  |  |  |  |  |  |  |  |  |
| Net Name | PKG Lengths | PCB Net Length | Differential Match | Pin of Connector | Pin of Connector | Net Name | PCB Net LeNgth | DiffereNtial Match | Net Name | PCB Net LeNgth | DiffereNtial Match | Total LeNgth | DiffereNtial Match |  |  |  |  |  |  |  |  |  |  |  |  |  |  |  |  |
| PCIE_REFCLK_S1_N |  | 11325.24 |  | A2 | A2 | PE_100M_CLK1_C_P | 442.79 |  | PE_100M_CLK1_P | 14558.9 |  | 26326.93 |  |  |  |  |  |  |  |  |  |  |  |  |  |  |  |  |  |
| PCIE_REFCLK_S1_P |  | 11325.68 | yes; within 1mil | A3 | A3 | PE_100M_CLK1_C_N | 442.66 | yes; within 1mil | PE_100M_CLK1_N | 14558.13 | yes; within 1mil | 26326.47 | yes; within 5mil |  |  |  |  |  |  |  |  |  |  |  |  |  |  |  |  |
| PCIE_REFCLK_S2_N |  | 10815.48 |  | B2 | B2 | PE_100M_CLK2_C_P | 388.25 |  | PE_100M_CLK2_P | 10303.299999999999 |  | 21507.03 |  |  |  |  |  |  |  |  |  |  |  |  |  |  |  |  |  |
| PCIE_REFCLK_S2_P |  | 10815.07 | yes; within 1mil | B3 | B3 | PE_100M_CLK2_C_N | 388.91 | yes; within 1mil | PE_100M_CLK2_N | 10303.459999999999 | yes; within 1mil | 21507.439999999999 | yes; within 5mil |  |  |  |  |  |  |  |  |  |  |  |  |  |  |  |  |
| PCIE_REFCLK_S3_N |  | 11897.06 |  | B76 | B76 | PE_100M_CLK3_C_P | 1310.1199999999999 |  | PE_100M_CLK3_P | 7707.7 |  | 20914.88 |  |  |  |  |  |  |  |  |  |  |  |  |  |  |  |  |  |
| PCIE_REFCLK_S3_P |  | 11896.73 | yes; within 1mil | B77 | B77 | PE_100M_CLK3_C_N | 1310.73 | yes; within 1mil | PE_100M_CLK3_N | 7707.67 | yes; within 1mil | 20915.129999999997 | yes; within 5mil |  |  |  |  |  |  |  |  |  |  |  |  |  |  |  |  |
| PCIE_REFCLK_S4_N |  | 12250.55 |  | A78 | A78 | PE_100M_CLK4_C_P | 251.28 |  | PE_100M_CLK4_P | 4009.89 |  | 16511.72 |  |  |  |  |  |  |  |  |  |  |  |  |  |  |  |  |  |
| PCIE_REFCLK_S4_P |  | 12250.8 | yes; within 1mil | A79 | A79 | PE_100M_CLK4_C_N | 251.18 | yes; within 1mil | PE_100M_CLK4_N | 4009.4 | yes; within 1mil | 16511.38 | yes; within 5mil |  |  |  |  |  |  |  |  |  |  |  |  |  |  |  |  |
| SW OF PEB(U1G_PM8546A-FEIP-GP) to BMC |  |  |  |  |  |  |  |  |  |  |  |  |  |  |  |  |  |  |  |  |  |  |  |  |  |  |  |  |  |
| Net Name | PKG Lengths | PCB Net Length | Differential Match | Net Name | PCB Net Length | Differential Match | Total LeNgth |  |  |  |  |  |  |  |  |  |  |  |  |  |  |  |  |  |  |  |  |  |  |
| PCIE_REFCLK_S5_N |  | 10329.67 |  | BMC_REFCLK_N | 1364.94 |  | 11694.61 |  |  |  |  |  |  |  |  |  |  |  |  |  |  |  |  |  |  |  |  |  |  |
| PCIE_REFCLK_S5_P |  | 10329.24 | yes; within 1mil | BMC_REFCLK_P | 1365.82 | yes; within 1mil | 11695.06 |  |  |  |  |  |  |  |  |  |  |  |  |  |  |  |  |  |  |  |  |  |  |
|  |  |  |  |  |  |  |  | PCISLT68-14-GP-U | SKT-SAS28-P15-PCIE25-2-GP |  |  |  |  |  |  |  |  |  |  |  |  |  |  |  |  |  |  |  |  |
| CLK BUFFER1 of PDPB(EU4_9ZXL1231AKLFT-GP) to SSD Slot |  |  |  |  |  |  |  | SFF-8639 Conn | SFF-8639 Conn | M.2 Conn |  |  |  |  |  |  |  |  |  |  |  |  |  |  |  |  |  |  |  |
| Net Name | PCB Net Length | Differential Match | Net Name | PCB Net Length | Differential Match | Total Length | Differential Match | Pin of Connector | Pin of Connector | Net Name | PCB Net Length | Differential Match | Total Length | Differential Match |  |  |  |  |  |  |  |  |  |  |  |  |  |  |  |
| PE_CLK_100M_DR9_2_R_P | 246.4 |  | PE_CLK100M_DR9_2_P | 2811.28 |  | 3057.6800000000003 |  | E1 | E1 | D85_PCIE_B_REFCLK_P | 966.45 |  | 4024.13 |  |  |  |  |  |  |  |  |  |  |  |  |  |  |  |  |
| PE_CLK_100M_DR9_2_R_N | 246.54 | yes; within 1mil | PE_CLK100M_DR9_2_N | 2810.35 | yes; within 1mil | 3056.89 | yes; within 1mil | E2 | E2 | D85_PCIE_B_REFCLK_N | 966.59 | yes; within 1mil | 4023.48 | yes; within 5mil |  |  |  |  |  |  |  |  |  |  |  |  |  |  |  |
| PE_CLK_100M_DR9_1_R_P | 183.04 |  | PE_CLK100M_DR9_1_P | 3476.01 |  | 3659.05 |  | E7 | E7 | D85_PCIE_A_REFCLK_P | 775.61 |  | 4434.66 |  |  |  |  |  |  |  |  |  |  |  |  |  |  |  |  |
| PE_CLK_100M_DR9_1_R_N | 183.06 | yes; within 1mil | PE_CLK100M_DR9_1_N | 3475.73 | yes; within 1mil | 3658.79 | yes; within 1mil | E8 | E8 | D85_PCIE_A_REFCLK_N | 776.54 | yes; within 1mil | 4435.33 | yes; within 5mil |  |  |  |  |  |  |  |  |  |  |  |  |  |  |  |
| PE_CLK_100M_DR14_2_R_P | 172.55 |  | PE_CLK100M_DR14_2_P | 4758.97 |  | 4931.5200000000004 |  | E1 | E1 | D85_PCIE_B_REFCLK_P | 966.45 |  | 5897.97 |  |  |  |  |  |  |  |  |  |  |  |  |  |  |  |  |
| PE_CLK_100M_DR14_2_R_N | 172.57 | yes; within 1mil | PE_CLK100M_DR14_2_N | 4758.8599999999997 | yes; within 1mil | 4931.4299999999994 | yes; within 1mil | E2 | E2 | D85_PCIE_B_REFCLK_N | 966.59 | yes; within 1mil | 5898.0199999999995 | yes; within 5mil |  |  |  |  |  |  |  |  |  |  |  |  |  |  |  |
| PE_CLK_100M_DR14_1_R_P | 229.2 |  | PE_CLK100M_DR14_1_P | 5256.84 |  | 5486.04 |  | E7 | E7 | D85_PCIE_A_REFCLK_P | 775.61 |  | 6261.65 |  |  |  |  |  |  |  |  |  |  |  |  |  |  |  |  |
| PE_CLK_100M_DR14_1_R_N | 229.2 | yes; within 1mil | PE_CLK100M_DR14_1_N | 5256.75 | yes; within 1mil | 5485.95 | yes; within 1mil | E8 | E8 | D85_PCIE_A_REFCLK_N | 776.54 | yes; within 1mil | 6262.49 | yes; within 5mil |  |  |  |  |  |  |  |  |  |  |  |  |  |  |  |
| PE_CLK_100M_DR8_2_R_P | 223.76 |  | PE_CLK100M_DR8_2_P | 3618.87 |  | 3842.63 |  | E1 | E1 | D85_PCIE_B_REFCLK_P | 966.45 |  | 4809.08 |  |  |  |  |  |  |  |  |  |  |  |  |  |  |  |  |
| PE_CLK_100M_DR8_2_R_N | 223.75 | yes; within 1mil | PE_CLK100M_DR8_2_N | 3618.98 | yes; within 1mil | 3842.73 | yes; within 1mil | E2 | E2 | D85_PCIE_B_REFCLK_N | 966.59 | yes; within 1mil | 4809.32 | yes; within 5mil |  |  |  |  |  |  |  |  |  |  |  |  |  |  |  |
| PE_CLK_100M_DR8_1_R_P | 172.56 |  | PE_CLK100M_DR8_1_P | 3434.25 |  | 3606.81 |  | E7 | E7 | D85_PCIE_A_REFCLK_P | 775.61 |  | 4382.42 |  |  |  |  |  |  |  |  |  |  |  |  |  |  |  |  |
| PE_CLK_100M_DR8_1_R_N | 172.55 | yes; within 1mil | PE_CLK100M_DR8_1_N | 3434.16 | yes; within 1mil | 3606.71 | yes; within 1mil | E8 | E8 | D85_PCIE_A_REFCLK_N | 776.54 | yes; within 1mil | 4383.25 | yes; within 5mil |  |  |  |  |  |  |  |  |  |  |  |  |  |  |  |
| PE_CLK_100M_DR13_2_R_P | 183.06 |  | PE_CLK100M_DR13_2_P | 3653.94 |  | 3837 |  | E1 | E1 | D85_PCIE_B_REFCLK_P | 966.45 |  | 4803.45 |  |  |  |  |  |  |  |  |  |  |  |  |  |  |  |  |
| PE_CLK_100M_DR13_2_R_N | 183.05 | yes; within 1mil | PE_CLK100M_DR13_2_N | 3654.04 | yes; within 1mil | 3837.09 | yes; within 1mil | E2 | E2 | D85_PCIE_B_REFCLK_N | 966.59 | yes; within 1mil | 4803.68 | yes; within 5mil |  |  |  |  |  |  |  |  |  |  |  |  |  |  |  |
| PE_CLK_100M_DR13_1_R_P | 246.55 |  | PE_CLK100M_DR13_1_P | 3477.96 |  | 3724.51 |  | E7 | E7 | D85_PCIE_A_REFCLK_P | 775.61 |  | 4500.12 |  |  |  |  |  |  |  |  |  |  |  |  |  |  |  |  |
| PE_CLK_100M_DR13_1_R_N | 246.41 | yes; within 1mil | PE_CLK100M_DR13_1_N | 3477.9 | yes; within 1mil | 3724.31 | yes; within 1mil | E8 | E8 | D85_PCIE_A_REFCLK_N | 776.54 | yes; within 1mil | 4500.8500000000004 | yes; within 5mil |  |  |  |  |  |  |  |  |  |  |  |  |  |  |  |
|  |  |  |  |  |  |  |  | PCISLT68-14-GP-U | SKT-SAS28-P15-PCIE25-2-GP |  |  |  |  |  |  |  |  |  |  |  |  |  |  |  |  |  |  |  |  |
| CLK BUFFER2 of PDPB(EU3_9ZXL1231AKLFT-GP) to SSD Slot |  |  |  |  |  |  |  | SFF-8639 Conn | SFF-8639 Conn | M.2 Conn |  |  |  |  |  |  |  |  |  |  |  |  |  |  |  |  |  |  |  |
| Net Name | PCB Net Length | Differential Match | Net Name | PCB Net Length | Differential Match | Total Length | Differential Match | Pin of Connector | Pin of Connector | Net Name | PCB Net Length | Differential Match | Total Length | Differential Match |  |  |  |  |  |  |  |  |  |  |  |  |  |  |  |
| PE_CLK_100M_DR4_2_R_P | 165.81 |  | PE_CLK100M_DR4_2_p | 9636.91 |  | 9802.7199999999993 |  | E1 | E1 | D85_PCIE_B_REFCLK_P | 966.45 |  | 10769.17 |  |  |  |  |  |  |  |  |  |  |  |  |  |  |  |  |
| PE_CLK_100M_DR4_2_R_N | 165.83 | yes; within 1mil | PE_CLK100M_DR4_2_n | 9636.5300000000007 | yes; within 1mil | 9802.36 | yes; within 1mil | E2 | E2 | D85_PCIE_B_REFCLK_N | 966.59 | yes; within 1mil | 10768.95 | yes; within 5mil |  |  |  |  |  |  |  |  |  |  |  |  |  |  |  |
| PE_CLK_100M_DR4_1_R_P | 175.16 |  | PE_CLK100M_DR4_1_p | 8072.26 |  | 8247.42 |  | E7 | E7 | D85_PCIE_A_REFCLK_P | 775.61 |  | 9023.0300000000007 |  |  |  |  |  |  |  |  |  |  |  |  |  |  |  |  |
| PE_CLK_100M_DR4_1_R_N | 174.18 | yes; within 1mil | PE_CLK100M_DR4_1_n | 8072.76 | yes; within 1mil | 8246.94 | yes; within 1mil | E8 | E8 | D85_PCIE_A_REFCLK_N | 776.54 | yes; within 1mil | 9023.48 | yes; within 5mil |  |  |  |  |  |  |  |  |  |  |  |  |  |  |  |
| PE_CLK_100M_DR3_2_R_P | 223.76 |  | PE_CLK100M_DR3_2_p | 7846.84 |  | 8070.6 |  | E1 | E1 | D85_PCIE_B_REFCLK_P | 966.45 |  | 9037.0500000000011 |  |  |  |  |  |  |  |  |  |  |  |  |  |  |  |  |
| PE_CLK_100M_DR3_2_R_N | 223.75 | yes; within 1mil | PE_CLK100M_DR3_2_n | 7846.2 | yes; within 1mil | 8069.95 | yes; within 1mil | E2 | E2 | D85_PCIE_B_REFCLK_N | 966.59 | yes; within 1mil | 9036.5399999999991 | yes; within 5mil |  |  |  |  |  |  |  |  |  |  |  |  |  |  |  |
| PE_CLK_100M_DR3_1_R_P | 172.56 |  | PE_CLK100M_DR3_1_p | 6664.8 |  | 6837.3600000000006 |  | E7 | E7 | D85_PCIE_A_REFCLK_P | 775.61 |  | 7612.97 |  |  |  |  |  |  |  |  |  |  |  |  |  |  |  |  |
| PE_CLK_100M_DR3_1_R_N | 173.39 | yes; within 1mil | PE_CLK100M_DR3_1_n | 6664.81 | yes; within 1mil | 6838.2000000000007 | yes; within 1mil | E8 | E8 | D85_PCIE_A_REFCLK_N | 776.54 | yes; within 1mil | 7614.7400000000007 | yes; within 5mil |  |  |  |  |  |  |  |  |  |  |  |  |  |  |  |
| PE_CLK_100M_DR7_2_R_P | 223.76 |  | PE_CLK100M_DR7_2_p | 3522.9 |  | 3746.66 |  | E1 | E1 | D85_PCIE_B_REFCLK_P | 966.45 |  | 4713.1099999999997 |  |  |  |  |  |  |  |  |  |  |  |  |  |  |  |  |
| PE_CLK_100M_DR7_2_R_N | 223.75 | yes; within 1mil | PE_CLK100M_DR7_2_n | 3523 | yes; within 1mil | 3746.75 | yes; within 1mil | E2 | E2 | D85_PCIE_B_REFCLK_N | 966.59 | yes; within 1mil | 4713.34 | yes; within 5mil |  |  |  |  |  |  |  |  |  |  |  |  |  |  |  |
| PE_CLK_100M_DR7_1_R_P | 172.56 |  | PE_CLK100M_DR7_1_p | 3255.75 |  | 3428.31 |  | E7 | E7 | D85_PCIE_A_REFCLK_P | 775.61 |  | 4203.92 |  |  |  |  |  |  |  |  |  |  |  |  |  |  |  |  |
| PE_CLK_100M_DR7_1_R_N | 172.55 | yes; within 1mil | PE_CLK100M_DR7_1_n | 3255.64 | yes; within 1mil | 3428.19 | yes; within 1mil | E8 | E8 | D85_PCIE_A_REFCLK_N | 776.54 | yes; within 1mil | 4204.7299999999996 | yes; within 5mil |  |  |  |  |  |  |  |  |  |  |  |  |  |  |  |
| PE_CLK_100M_DR12_2_R_P | 183.06 |  | PE_CLK100M_DR12_2_p | 3553.44 |  | 3736.5 |  | E1 | E1 | D85_PCIE_B_REFCLK_P | 966.45 |  | 4702.95 |  |  |  |  |  |  |  |  |  |  |  |  |  |  |  |  |
| PE_CLK_100M_DR12_2_R_N | 183.05 | yes; within 1mil | PE_CLK100M_DR12_2_n | 3553.73 | yes; within 1mil | 3736.78 | yes; within 1mil | E2 | E2 | D85_PCIE_B_REFCLK_N | 966.59 | yes; within 1mil | 4703.37 | yes; within 5mil |  |  |  |  |  |  |  |  |  |  |  |  |  |  |  |
| PE_CLK_100M_DR12_1_R_P | 247.14 |  | PE_CLK100M_DR12_1_p | 3161.3 |  | 3408.44 |  | E7 | E7 | D85_PCIE_A_REFCLK_P | 775.61 |  | 4184.05 |  |  |  |  |  |  |  |  |  |  |  |  |  |  |  |  |
| PE_CLK_100M_DR12_1_R_N | 247.34 | yes; within 1mil | PE_CLK100M_DR12_1_n | 3161.41 | yes; within 1mil | 3408.75 | yes; within 1mil | E8 | E8 | D85_PCIE_A_REFCLK_N | 776.54 | yes; within 1mil | 4185.29 | yes; within 5mil |  |  |  |  |  |  |  |  |  |  |  |  |  |  |  |
|  |  |  |  |  |  |  |  | PCISLT68-14-GP-U | SKT-SAS28-P15-PCIE25-2-GP |  |  |  |  |  |  |  |  |  |  |  |  |  |  |  |  |  |  |  |  |
| CLK BUFFER3 of PDPB(EU2_9ZXL1231AKLFT-GP) to SSD Slot |  |  |  |  |  |  |  | SFF-8639 Conn | SFF-8639 Conn | M.2 Conn |  |  |  |  |  |  |  |  |  |  |  |  |  |  |  |  |  |  |  |
| Net Name | PCB Net LeNgth | DiffereNtial Match | Net Name | PCB Net LeNgth | DiffereNtial Match | Total Length | DiffereNtial Match | Pin of Connector | Pin of Connector | Net Name | PCB Net Length | Differential Match | Total Length | Differential Match |  |  |  |  |  |  |  |  |  |  |  |  |  |  |  |
| PE_CLK_100M_DR2_2_R_P | 172.55 |  | PE_CLK100M_DR2_2_P | 7376.67 |  | 7549.22 |  | E1 | E1 | D85_PCIE_B_REFCLK_P | 966.45 |  | 8515.67 |  |  |  |  |  |  |  |  |  |  |  |  |  |  |  |  |
| PE_CLK_100M_DR2_2_R_N | 172.56 | yes; within 1mil | PE_CLK100M_DR2_2_N | 7376.49 | yes; within 1mil | 7549.05 | yes; within 1mil | E2 | E2 | D85_PCIE_B_REFCLK_N | 966.59 | yes; within 1mil | 8515.64 | yes; within 5mil |  |  |  |  |  |  |  |  |  |  |  |  |  |  |  |
| PE_CLK_100M_DR2_1_R_P | 232.13 |  | PE_CLK100M_DR2_1_P | 5815.88 |  | 6048.01 |  | E7 | E7 | D85_PCIE_A_REFCLK_P | 775.61 |  | 6823.62 |  |  |  |  |  |  |  |  |  |  |  |  |  |  |  |  |
| PE_CLK_100M_DR2_1_R_N | 232.14 | yes; within 1mil | PE_CLK100M_DR2_1_N | 5816.82 | yes; within 1mil | 6048.96 | yes; within 1mil | E8 | E8 | D85_PCIE_A_REFCLK_N | 776.54 | yes; within 1mil | 6825.5 | yes; within 5mil |  |  |  |  |  |  |  |  |  |  |  |  |  |  |  |
| PE_CLK_100M_DR1_2_R_P | 172.58 |  | PE_CLK100M_DR1_2_P | 6885.11 |  | 7057.69 |  | E1 | E1 | D85_PCIE_B_REFCLK_P | 966.45 |  | 8024.1399999999994 |  |  |  |  |  |  |  |  |  |  |  |  |  |  |  |  |
| PE_CLK_100M_DR1_2_R_N | 172.56 | yes; within 1mil | PE_CLK100M_DR1_2_N | 6885.78 | yes; within 1mil | 7058.34 | yes; within 1mil | E2 | E2 | D85_PCIE_B_REFCLK_N | 966.59 | yes; within 1mil | 8024.93 | yes; within 5mil |  |  |  |  |  |  |  |  |  |  |  |  |  |  |  |
| PE_CLK_100M_DR1_1_R_P | 229.78 |  | PE_CLK100M_DR1_1_P | 5603.73 |  | 5833.5099999999993 |  | E7 | E7 | D85_PCIE_A_REFCLK_P | 775.61 |  | 6609.119999999999 |  |  |  |  |  |  |  |  |  |  |  |  |  |  |  |  |
| PE_CLK_100M_DR1_1_R_N | 229.78 | yes; within 1mil | PE_CLK100M_DR1_1_N | 5603.73 | yes; within 1mil | 5833.5099999999993 | yes; within 1mil | E8 | E8 | D85_PCIE_A_REFCLK_N | 776.54 | yes; within 1mil | 6610.0499999999993 | yes; within 5mil |  |  |  |  |  |  |  |  |  |  |  |  |  |  |  |
| PE_CLK_100M_DR6_2_R_P | 232.02 |  | PE_CLK100M_DR6_2_P | 3656.81 |  | 3888.83 |  | E1 | E1 | D85_PCIE_B_REFCLK_P | 966.45 |  | 4855.28 |  |  |  |  |  |  |  |  |  |  |  |  |  |  |  |  |
| PE_CLK_100M_DR6_2_R_N | 232.01 | yes; within 1mil | PE_CLK100M_DR6_2_N | 3656.9 | yes; within 1mil | 3888.91 | yes; within 1mil | E2 | E2 | D85_PCIE_B_REFCLK_N | 966.59 | yes; within 1mil | 4855.5 | yes; within 5mil |  |  |  |  |  |  |  |  |  |  |  |  |  |  |  |
| PE_CLK_100M_DR6_1_R_P | 172.56 |  | PE_CLK100M_DR6_1_P | 3403.66 |  | 3576.22 |  | E7 | E7 | D85_PCIE_A_REFCLK_P | 775.61 |  | 4351.83 |  |  |  |  |  |  |  |  |  |  |  |  |  |  |  |  |
| PE_CLK_100M_DR6_1_R_N | 172.55 | yes; within 1mil | PE_CLK100M_DR6_1_N | 3403.55 | yes; within 1mil | 3576.1000000000004 | yes; within 1mil | E8 | E8 | D85_PCIE_A_REFCLK_N | 776.54 | yes; within 1mil | 4352.6400000000003 | yes; within 5mil |  |  |  |  |  |  |  |  |  |  |  |  |  |  |  |
| PE_CLK_100M_DR11_2_R_P | 188.33 |  | PE_CLK100M_DR11_2_P | 3692.56 |  | 3880.89 |  | E1 | E1 | D85_PCIE_B_REFCLK_P | 966.45 |  | 4847.34 |  |  |  |  |  |  |  |  |  |  |  |  |  |  |  |  |
| PE_CLK_100M_DR11_2_R_N | 188.33 | yes; within 1mil | PE_CLK100M_DR11_2_N | 3692.85 | yes; within 1mil | 3881.18 | yes; within 1mil | E2 | E2 | D85_PCIE_B_REFCLK_N | 966.59 | yes; within 1mil | 4847.7699999999995 | yes; within 5mil |  |  |  |  |  |  |  |  |  |  |  |  |  |  |  |
| PE_CLK_100M_DR11_1_R_P | 240.11 |  | PE_CLK100M_DR11_1_P | 3525.6 |  | 3765.71 |  | E7 | E7 | D85_PCIE_A_REFCLK_P | 775.61 |  | 4541.32 |  |  |  |  |  |  |  |  |  |  |  |  |  |  |  |  |
| PE_CLK_100M_DR11_1_R_N | 239.87 | yes; within 1mil | PE_CLK100M_DR11_1_N | 3526.55 | yes; within 1mil | 3766.42 | yes; within 1mil | E8 | E8 | D85_PCIE_A_REFCLK_N | 776.54 | yes; within 1mil | 4542.96 | yes; within 5mil |  |  |  |  |  |  |  |  |  |  |  |  |  |  |  |
|  |  |  |  |  |  |  |  | PCISLT68-14-GP-U | SKT-SAS28-P15-PCIE25-2-GP |  |  |  |  |  |  |  |  |  |  |  |  |  |  |  |  |  |  |  |  |
| CLK BUFFER4 of PDPB(EU1_9ZXL1231AKLFT-GP) to SSD Slot |  |  |  |  |  |  |  | SFF-8639 Conn | SFF-8639 Conn | M.2 Conn |  |  |  |  |  |  |  |  |  |  |  |  |  |  |  |  |  |  |  |
| Net Name | PCB Net LeNgth | DiffereNtial Match | Net Name | PCB Net LeNgth | DiffereNtial Match | Total Length | DiffereNtial Match | Pin of Connector | Pin of Connector | Net Name | PCB Net Length | Differential Match | Total Length | Differential Match |  |  |  |  |  |  |  |  |  |  |  |  |  |  |  |
| PE_CLK_100M_DR10_2_R_P | 243.56 |  | PE_CLK100M_DR10_2_P | 3677.01 |  | 3920.57 |  | E1 | E1 | D85_PCIE_B_REFCLK_P | 966.45 |  | 4887.0200000000004 |  |  |  |  |  |  |  |  |  |  |  |  |  |  |  |  |
| PE_CLK_100M_DR10_2_R_N | 243.2 | yes; within 1mil | PE_CLK100M_DR10_2_N | 3677.1 | yes; within 1mil | 3920.2999999999997 | yes; within 1mil | E2 | E2 | D85_PCIE_B_REFCLK_N | 966.59 | yes; within 1mil | 4886.8899999999994 | yes; within 5mil |  |  |  |  |  |  |  |  |  |  |  |  |  |  |  |
| PE_CLK_100M_DR10_1_R_P | 183.04 |  | PE_CLK100M_DR10_1_P | 4096.16 |  | 4279.2 |  | E7 | E7 | D85_PCIE_A_REFCLK_P | 775.61 |  | 5054.8099999999995 |  |  |  |  |  |  |  |  |  |  |  |  |  |  |  |  |
| PE_CLK_100M_DR10_1_R_N | 183.06 | yes; within 1mil | PE_CLK100M_DR10_1_N | 4095.23 | yes; within 1mil | 4278.29 | yes; within 1mil | E8 | E8 | D85_PCIE_A_REFCLK_N | 776.54 | yes; within 1mil | 5054.83 | yes; within 5mil |  |  |  |  |  |  |  |  |  |  |  |  |  |  |  |
| PE_CLK_100M_DR0_2_R_P | 172.55 |  | PE_CLK100M_DR0_2_P | 6519.83 |  | 6692.38 |  | E1 | E1 | D85_PCIE_B_REFCLK_P | 966.45 |  | 7658.83 |  |  |  |  |  |  |  |  |  |  |  |  |  |  |  |  |
| PE_CLK_100M_DR0_2_R_N | 172.57 | yes; within 1mil | PE_CLK100M_DR0_2_N | 6519.18 | yes; within 1mil | 6691.75 | yes; within 1mil | E2 | E2 | D85_PCIE_B_REFCLK_N | 966.59 | yes; within 1mil | 7658.34 | yes; within 5mil |  |  |  |  |  |  |  |  |  |  |  |  |  |  |  |
| PE_CLK_100M_DR0_1_R_P | 231.09 |  | PE_CLK100M_DR0_1_P | 5342.74 |  | 5573.83 |  | E7 | E7 | D85_PCIE_A_REFCLK_P | 775.61 |  | 6349.44 |  |  |  |  |  |  |  |  |  |  |  |  |  |  |  |  |
| PE_CLK_100M_DR0_1_R_N | 231.09 | yes; within 1mil | PE_CLK100M_DR0_1_N | 5342.75 | yes; within 1mil | 5573.84 | yes; within 1mil | E8 | E8 | D85_PCIE_A_REFCLK_N | 776.54 | yes; within 1mil | 6350.38 | yes; within 5mil |  |  |  |  |  |  |  |  |  |  |  |  |  |  |  |
| PE_CLK_100M_DR5_2_R_P | 183.06 |  | PE_CLK100M_DR5_2_P | 2886.98 |  | 3070.04 |  | E1 | E1 | D85_PCIE_B_REFCLK_P | 966.45 |  | 4036.49 |  |  |  |  |  |  |  |  |  |  |  |  |  |  |  |  |
| PE_CLK_100M_DR5_2_R_N | 183.05 | yes; within 1mil | PE_CLK100M_DR5_2_N | 2887.91 | yes; within 1mil | 3070.96 | yes; within 1mil | E2 | E2 | D85_PCIE_B_REFCLK_N | 966.59 | yes; within 1mil | 4037.55 | yes; within 5mil |  |  |  |  |  |  |  |  |  |  |  |  |  |  |  |
| PE_CLK_100M_DR5_1_R_P | 238.57 |  | PE_CLK100M_DR5_1_P | 2777.05 |  | 3015.6200000000003 |  | E7 | E7 | D85_PCIE_A_REFCLK_P | 775.61 |  | 3791.2300000000005 |  |  |  |  |  |  |  |  |  |  |  |  |  |  |  |  |
| PE_CLK_100M_DR5_1_R_N | 238.59 | yes; within 1mil | PE_CLK100M_DR5_1_N | 2776.13 | yes; within 1mil | 3014.7200000000003 | yes; within 1mil | E8 | E8 | D85_PCIE_A_REFCLK_N | 776.54 | yes; within 1mil | 3791.26 | yes; within 5mil |  |  |  |  |  |  |  |  |  |  |  |  |  |  |  |
